(kicad_pcb
	(version 20260206)
	(generator "pcbnew")
	(generator_version "10.0")
	(general
		(thickness 1.6)
		(legacy_teardrops no)
	)
	(paper "A4")
	(title_block
		(title "01162023_DA0F0TEBIF0_F0T_Expander_BD_F_brd_V02_OCP.brd")
		(comment 1 "Grand Teton / footprints 5878-5883 of 9728")
	)
	(layers
		(0 "F.Cu" signal "TOP")
		(4 "In1.Cu" signal "GND")
		(6 "In2.Cu" signal "VCC")
		(8 "In3.Cu" signal "VCC1")
		(10 "In4.Cu" signal "GND1")
		(12 "In5.Cu" signal "IN1")
		(14 "In6.Cu" signal "GND2")
		(16 "In7.Cu" signal "IN2")
		(18 "In8.Cu" signal "GND3")
		(20 "In9.Cu" signal "IN3")
		(22 "In10.Cu" signal "GND4")
		(24 "In11.Cu" signal "IN4")
		(26 "In12.Cu" signal "GND5")
		(28 "In13.Cu" signal "IN5")
		(30 "In14.Cu" signal "GND6")
		(32 "In15.Cu" signal "IN6")
		(34 "In16.Cu" signal "GND7")
		(2 "B.Cu" signal "BOTTOM")
		(9 "F.Adhes" user "F.Adhesive")
		(11 "B.Adhes" user "B.Adhesive")
		(13 "F.Paste" user "Package Geometry/Pastemask Top")
		(15 "B.Paste" user "Package Geometry/Pastemask Bottom")
		(5 "F.SilkS" user "Ref Des/Silkscreen Top")
		(7 "B.SilkS" user "Ref Des/Silkscreen Bottom")
		(1 "F.Mask" user "Board Geometry/Soldermask Top")
		(3 "B.Mask" user "Board Geometry/Soldermask Bottom")
		(17 "Dwgs.User" user "User.Drawings")
		(19 "Cmts.User" user "User.Comments")
		(21 "Eco1.User" user "User.Eco1")
		(23 "Eco2.User" user "User.Eco2")
		(25 "Edge.Cuts" user "Board Geometry/Outline")
		(27 "Margin" user)
		(31 "F.CrtYd" user "Package Geometry/Place Bound Top")
		(29 "B.CrtYd" user "Package Geometry/Place Bound Bottom")
		(35 "F.Fab" user "Ref Des/Assembly Top")
		(33 "B.Fab" user "Ref Des/Assembly Bottom")
	)
	(footprint ""
		(layer "F.Cu")
		(at 371.956584 -20.467574 180)
		(property "Reference" "R1717"
			(at 0 0 180)
			(layer "F.SilkS")
			(hide yes)
			(effects
				(font
					(size 1.27 1.27)
				)
			)
		)
		(property "Value" ""
			(at 0 0 180)
			(layer "F.Fab")
			(effects
				(font
					(size 1.27 1.27)
				)
			)
		)
		(duplicate_pad_numbers_are_jumpers no)
		(fp_line
			(start 0.7874 0.4064)
			(end -0.7874 0.4064)
			(stroke
				(width 0.1524)
				(type default)
			)
			(layer "F.SilkS")
		)
		(fp_line
			(start 0.7874 -0.4064)
			(end 0.7874 0.4064)
			(stroke
				(width 0.1524)
				(type default)
			)
			(layer "F.SilkS")
		)
		(fp_line
			(start -0.7874 0.4064)
			(end -0.7874 -0.4064)
			(stroke
				(width 0.1524)
				(type default)
			)
			(layer "F.SilkS")
		)
		(fp_line
			(start -0.7874 -0.4064)
			(end 0.7874 -0.4064)
			(stroke
				(width 0.1524)
				(type default)
			)
			(layer "F.SilkS")
		)
		(fp_line
			(start 0.67945 0.3048)
			(end 0.120396 0.3048)
			(stroke
				(width 0.1)
				(type default)
			)
			(layer "F.Fab")
		)
		(fp_line
			(start 0.67945 -0.3048)
			(end 0.67945 0.3048)
			(stroke
				(width 0.1)
				(type default)
			)
			(layer "F.Fab")
		)
		(fp_line
			(start 0.12065 -0.2794)
			(end 0.12065 -0.3048)
			(stroke
				(width 0.1)
				(type default)
			)
			(layer "F.Fab")
		)
		(fp_line
			(start 0.12065 -0.3048)
			(end 0.67945 -0.3048)
			(stroke
				(width 0.1)
				(type default)
			)
			(layer "F.Fab")
		)
		(fp_line
			(start 0.120396 0.3048)
			(end 0.120396 0.2794)
			(stroke
				(width 0.1)
				(type default)
			)
			(layer "F.Fab")
		)
		(fp_line
			(start 0.120396 0.2794)
			(end -0.12065 0.2794)
			(stroke
				(width 0.1)
				(type default)
			)
			(layer "F.Fab")
		)
		(fp_line
			(start -0.12065 0.3048)
			(end -0.67945 0.3048)
			(stroke
				(width 0.1)
				(type default)
			)
			(layer "F.Fab")
		)
		(fp_line
			(start -0.12065 0.2794)
			(end -0.12065 0.3048)
			(stroke
				(width 0.1)
				(type default)
			)
			(layer "F.Fab")
		)
		(fp_line
			(start -0.12065 -0.2794)
			(end 0.12065 -0.2794)
			(stroke
				(width 0.1)
				(type default)
			)
			(layer "F.Fab")
		)
		(fp_line
			(start -0.12065 -0.305054)
			(end -0.12065 -0.2794)
			(stroke
				(width 0.1)
				(type default)
			)
			(layer "F.Fab")
		)
		(fp_line
			(start -0.67945 0.3048)
			(end -0.67945 -0.305054)
			(stroke
				(width 0.1)
				(type default)
			)
			(layer "F.Fab")
		)
		(fp_line
			(start -0.67945 -0.305054)
			(end -0.12065 -0.305054)
			(stroke
				(width 0.1)
				(type default)
			)
			(layer "F.Fab")
		)
		(pad "1" smd circle
			(at -0.40005 0 180)
			(size 0 0)
			(layers "F.Cu" "F.Mask" "F.Paste")
			(net "P3V3_SSD12")
		)
		(pad "2" smd circle
			(at 0.40005 0 180)
			(size 0 0)
			(layers "F.Cu" "F.Mask" "F.Paste")
			(net "SMB_ISO_SSD12_SDA")
		)
	)
	(footprint ""
		(layer "F.Cu")
		(at 144.975326 -64.102234 180)
		(property "Reference" "PR7068"
			(at 0 0 180)
			(layer "F.SilkS")
			(hide yes)
			(effects
				(font
					(size 1.27 1.27)
				)
			)
		)
		(property "Value" ""
			(at 0 0 180)
			(layer "F.Fab")
			(effects
				(font
					(size 1.27 1.27)
				)
			)
		)
		(duplicate_pad_numbers_are_jumpers no)
		(fp_line
			(start 0.7874 0.4064)
			(end -0.7874 0.4064)
			(stroke
				(width 0.1524)
				(type default)
			)
			(layer "F.SilkS")
		)
		(fp_line
			(start 0.7874 -0.4064)
			(end 0.7874 0.4064)
			(stroke
				(width 0.1524)
				(type default)
			)
			(layer "F.SilkS")
		)
		(fp_line
			(start -0.7874 0.4064)
			(end -0.7874 -0.4064)
			(stroke
				(width 0.1524)
				(type default)
			)
			(layer "F.SilkS")
		)
		(fp_line
			(start -0.7874 -0.4064)
			(end 0.7874 -0.4064)
			(stroke
				(width 0.1524)
				(type default)
			)
			(layer "F.SilkS")
		)
		(fp_line
			(start 0.67945 0.3048)
			(end 0.120396 0.3048)
			(stroke
				(width 0.1)
				(type default)
			)
			(layer "F.Fab")
		)
		(fp_line
			(start 0.67945 -0.3048)
			(end 0.67945 0.3048)
			(stroke
				(width 0.1)
				(type default)
			)
			(layer "F.Fab")
		)
		(fp_line
			(start 0.12065 -0.2794)
			(end 0.12065 -0.3048)
			(stroke
				(width 0.1)
				(type default)
			)
			(layer "F.Fab")
		)
		(fp_line
			(start 0.12065 -0.3048)
			(end 0.67945 -0.3048)
			(stroke
				(width 0.1)
				(type default)
			)
			(layer "F.Fab")
		)
		(fp_line
			(start 0.120396 0.3048)
			(end 0.120396 0.2794)
			(stroke
				(width 0.1)
				(type default)
			)
			(layer "F.Fab")
		)
		(fp_line
			(start 0.120396 0.2794)
			(end -0.12065 0.2794)
			(stroke
				(width 0.1)
				(type default)
			)
			(layer "F.Fab")
		)
		(fp_line
			(start -0.12065 0.3048)
			(end -0.67945 0.3048)
			(stroke
				(width 0.1)
				(type default)
			)
			(layer "F.Fab")
		)
		(fp_line
			(start -0.12065 0.2794)
			(end -0.12065 0.3048)
			(stroke
				(width 0.1)
				(type default)
			)
			(layer "F.Fab")
		)
		(fp_line
			(start -0.12065 -0.2794)
			(end 0.12065 -0.2794)
			(stroke
				(width 0.1)
				(type default)
			)
			(layer "F.Fab")
		)
		(fp_line
			(start -0.12065 -0.305054)
			(end -0.12065 -0.2794)
			(stroke
				(width 0.1)
				(type default)
			)
			(layer "F.Fab")
		)
		(fp_line
			(start -0.67945 0.3048)
			(end -0.67945 -0.305054)
			(stroke
				(width 0.1)
				(type default)
			)
			(layer "F.Fab")
		)
		(fp_line
			(start -0.67945 -0.305054)
			(end -0.12065 -0.305054)
			(stroke
				(width 0.1)
				(type default)
			)
			(layer "F.Fab")
		)
		(pad "1" smd circle
			(at -0.40005 0 180)
			(size 0 0)
			(layers "F.Cu" "F.Mask" "F.Paste")
			(net "P12V_SSD5_PG_G1")
		)
		(pad "2" smd circle
			(at 0.40005 0 180)
			(size 0 0)
			(layers "F.Cu" "F.Mask" "F.Paste")
			(net "GND")
		)
	)
	(footprint ""
		(layer "F.Cu")
		(at 254.671322 -395.293596 180)
		(property "Reference" "PD1"
			(at 3.719576 4.10464 0)
			(unlocked yes)
			(layer "F.SilkS")
			(effects
				(font
					(size 0.7874 0.5842)
					(thickness 0.1524)
				)
			)
		)
		(property "Value" ""
			(at 0 0 180)
			(layer "F.Fab")
			(effects
				(font
					(size 1.27 1.27)
				)
			)
		)
		(duplicate_pad_numbers_are_jumpers no)
		(fp_line
			(start 5.4102 3.109976)
			(end 5.4102 -3.109976)
			(stroke
				(width 0.1524)
				(type default)
			)
			(layer "F.SilkS")
		)
		(fp_line
			(start 5.4102 -3.109976)
			(end 4.783074 -3.109976)
			(stroke
				(width 0.1524)
				(type default)
			)
			(layer "F.SilkS")
		)
		(fp_line
			(start 5.313426 -3.109976)
			(end 5.313426 3.109976)
			(stroke
				(width 0.1524)
				(type default)
			)
			(layer "F.SilkS")
		)
		(fp_line
			(start 5.262626 -3.109976)
			(end 5.262626 3.109976)
			(stroke
				(width 0.1524)
				(type default)
			)
			(layer "F.SilkS")
		)
		(fp_line
			(start 5.211826 -3.109976)
			(end 5.211826 3.109976)
			(stroke
				(width 0.1524)
				(type default)
			)
			(layer "F.SilkS")
		)
		(fp_line
			(start 5.110226 -3.109976)
			(end 5.110226 3.109976)
			(stroke
				(width 0.1524)
				(type default)
			)
			(layer "F.SilkS")
		)
		(fp_line
			(start 5.008626 -3.109976)
			(end 5.008626 3.109976)
			(stroke
				(width 0.1524)
				(type default)
			)
			(layer "F.SilkS")
		)
		(fp_line
			(start 4.932426 -3.109976)
			(end 4.932426 3.109976)
			(stroke
				(width 0.1524)
				(type default)
			)
			(layer "F.SilkS")
		)
		(fp_line
			(start 4.805426 -3.109976)
			(end 4.805426 3.109976)
			(stroke
				(width 0.1524)
				(type default)
			)
			(layer "F.SilkS")
		)
		(fp_line
			(start 4.794504 3.109976)
			(end 3.554984 3.109976)
			(stroke
				(width 0.1524)
				(type default)
			)
			(layer "F.SilkS")
		)
		(fp_line
			(start 4.769104 3.109976)
			(end -4.664456 3.109976)
			(stroke
				(width 0.1524)
				(type default)
			)
			(layer "F.SilkS")
		)
		(fp_line
			(start 4.743704 3.109976)
			(end 5.4102 3.109976)
			(stroke
				(width 0.1524)
				(type default)
			)
			(layer "F.SilkS")
		)
		(fp_line
			(start 4.743704 3.109976)
			(end 4.6101 3.109976)
			(stroke
				(width 0.1524)
				(type default)
			)
			(layer "F.SilkS")
		)
		(fp_line
			(start 4.715002 3.035554)
			(end 4.7117 2.984754)
			(stroke
				(width 0.1524)
				(type default)
			)
			(layer "F.SilkS")
		)
		(fp_line
			(start 4.70535 -3.109976)
			(end 4.70535 3.109976)
			(stroke
				(width 0.1524)
				(type default)
			)
			(layer "F.SilkS")
		)
		(fp_line
			(start 4.70535 -3.109976)
			(end 4.70535 3.109976)
			(stroke
				(width 0.1524)
				(type default)
			)
			(layer "F.SilkS")
		)
		(fp_line
			(start 4.70535 -3.109976)
			(end 4.70535 3.109976)
			(stroke
				(width 0.1524)
				(type default)
			)
			(layer "F.SilkS")
		)
		(fp_line
			(start 4.695444 -3.109976)
			(end 4.695444 3.109976)
			(stroke
				(width 0.1524)
				(type default)
			)
			(layer "F.SilkS")
		)
		(fp_line
			(start 4.6101 -3.109976)
			(end 4.283202 -3.109976)
			(stroke
				(width 0.1524)
				(type default)
			)
			(layer "F.SilkS")
		)
		(fp_line
			(start 4.511802 -3.109976)
			(end 4.207002 -3.109976)
			(stroke
				(width 0.1524)
				(type default)
			)
			(layer "F.SilkS")
		)
		(fp_line
			(start 4.183126 -3.109976)
			(end 4.794504 -3.109976)
			(stroke
				(width 0.1524)
				(type default)
			)
			(layer "F.SilkS")
		)
		(fp_line
			(start 4.156202 3.109976)
			(end 4.183126 3.109976)
			(stroke
				(width 0.1524)
				(type default)
			)
			(layer "F.SilkS")
		)
		(fp_line
			(start 0.762 1.27)
			(end 0.762 -1.27)
			(stroke
				(width 0.1524)
				(type default)
			)
			(layer "F.SilkS")
		)
		(fp_line
			(start 0.762 0)
			(end 1.2192 0)
			(stroke
				(width 0.1524)
				(type default)
			)
			(layer "F.SilkS")
		)
		(fp_line
			(start 0.762 0)
			(end -0.508 1.016)
			(stroke
				(width 0.1524)
				(type default)
			)
			(layer "F.SilkS")
		)
		(fp_line
			(start -0.508 1.016)
			(end -0.508 -1.016)
			(stroke
				(width 0.1524)
				(type default)
			)
			(layer "F.SilkS")
		)
		(fp_line
			(start -0.508 -1.016)
			(end 0.762 0)
			(stroke
				(width 0.1524)
				(type default)
			)
			(layer "F.SilkS")
		)
		(fp_line
			(start -1.0668 0)
			(end -0.6096 0)
			(stroke
				(width 0.1524)
				(type default)
			)
			(layer "F.SilkS")
		)
		(fp_line
			(start -4.664456 3.109976)
			(end -4.664456 -3.109976)
			(stroke
				(width 0.1524)
				(type default)
			)
			(layer "F.SilkS")
		)
		(fp_line
			(start -4.664456 -3.109976)
			(end 4.743704 -3.109976)
			(stroke
				(width 0.1524)
				(type default)
			)
			(layer "F.SilkS")
		)
		(fp_line
			(start 4.065016 3.109976)
			(end -4.065016 3.109976)
			(stroke
				(width 0.1)
				(type default)
			)
			(layer "F.Fab")
		)
		(fp_line
			(start 4.065016 -3.109976)
			(end 4.065016 3.109976)
			(stroke
				(width 0.1)
				(type default)
			)
			(layer "F.Fab")
		)
		(fp_line
			(start -4.065016 3.109976)
			(end -4.065016 -3.109976)
			(stroke
				(width 0.1)
				(type default)
			)
			(layer "F.Fab")
		)
		(fp_line
			(start -4.065016 -3.109976)
			(end 4.065016 -3.109976)
			(stroke
				(width 0.1)
				(type default)
			)
			(layer "F.Fab")
		)
		(fp_text user "-"
			(at 6.084316 -3.33248 0)
			(unlocked yes)
			(layer "F.SilkS")
			(effects
				(font
					(size 1.905 1.4224)
					(thickness 0.1524)
				)
				(justify left)
			)
		)
		(fp_text user "+"
			(at -1.90246 -3.616706 0)
			(unlocked yes)
			(layer "F.SilkS")
			(effects
				(font
					(size 1.905 1.4224)
					(thickness 0.1524)
				)
				(justify left)
			)
		)
		(fp_text user "-"
			(at 6.643624 0.40005 0)
			(unlocked yes)
			(layer "F.Fab")
			(effects
				(font
					(size 1.905 1.4224)
					(thickness 0.1524)
				)
				(justify left)
			)
		)
		(fp_text user "+"
			(at -4.5974 0.24765 0)
			(unlocked yes)
			(layer "F.Fab")
			(effects
				(font
					(size 1.905 1.4224)
					(thickness 0.1524)
				)
				(justify left)
			)
		)
		(pad "A" smd rect
			(at -3.299968 0)
			(size 2.413 3.302)
			(layers "F.Cu" "F.Mask" "F.Paste")
			(net "GND")
		)
		(pad "C" smd rect
			(at 3.299968 0)
			(size 2.413 3.302)
			(layers "F.Cu" "F.Mask" "F.Paste")
			(net "P12V_STBY_FUSE")
		)
	)
	(footprint ""
		(layer "F.Cu")
		(at 213.70671 -225.42246 180)
		(property "Reference" "R1488"
			(at 0 0 180)
			(layer "F.SilkS")
			(hide yes)
			(effects
				(font
					(size 1.27 1.27)
				)
			)
		)
		(property "Value" ""
			(at 0 0 180)
			(layer "F.Fab")
			(effects
				(font
					(size 1.27 1.27)
				)
			)
		)
		(duplicate_pad_numbers_are_jumpers no)
		(fp_line
			(start 0.7874 0.4064)
			(end -0.7874 0.4064)
			(stroke
				(width 0.1524)
				(type default)
			)
			(layer "F.SilkS")
		)
		(fp_line
			(start 0.7874 -0.4064)
			(end 0.7874 0.4064)
			(stroke
				(width 0.1524)
				(type default)
			)
			(layer "F.SilkS")
		)
		(fp_line
			(start -0.7874 0.4064)
			(end -0.7874 -0.4064)
			(stroke
				(width 0.1524)
				(type default)
			)
			(layer "F.SilkS")
		)
		(fp_line
			(start -0.7874 -0.4064)
			(end 0.7874 -0.4064)
			(stroke
				(width 0.1524)
				(type default)
			)
			(layer "F.SilkS")
		)
		(fp_line
			(start 0.67945 0.3048)
			(end 0.120396 0.3048)
			(stroke
				(width 0.1)
				(type default)
			)
			(layer "F.Fab")
		)
		(fp_line
			(start 0.67945 -0.3048)
			(end 0.67945 0.3048)
			(stroke
				(width 0.1)
				(type default)
			)
			(layer "F.Fab")
		)
		(fp_line
			(start 0.12065 -0.2794)
			(end 0.12065 -0.3048)
			(stroke
				(width 0.1)
				(type default)
			)
			(layer "F.Fab")
		)
		(fp_line
			(start 0.12065 -0.3048)
			(end 0.67945 -0.3048)
			(stroke
				(width 0.1)
				(type default)
			)
			(layer "F.Fab")
		)
		(fp_line
			(start 0.120396 0.3048)
			(end 0.120396 0.2794)
			(stroke
				(width 0.1)
				(type default)
			)
			(layer "F.Fab")
		)
		(fp_line
			(start 0.120396 0.2794)
			(end -0.12065 0.2794)
			(stroke
				(width 0.1)
				(type default)
			)
			(layer "F.Fab")
		)
		(fp_line
			(start -0.12065 0.3048)
			(end -0.67945 0.3048)
			(stroke
				(width 0.1)
				(type default)
			)
			(layer "F.Fab")
		)
		(fp_line
			(start -0.12065 0.2794)
			(end -0.12065 0.3048)
			(stroke
				(width 0.1)
				(type default)
			)
			(layer "F.Fab")
		)
		(fp_line
			(start -0.12065 -0.2794)
			(end 0.12065 -0.2794)
			(stroke
				(width 0.1)
				(type default)
			)
			(layer "F.Fab")
		)
		(fp_line
			(start -0.12065 -0.305054)
			(end -0.12065 -0.2794)
			(stroke
				(width 0.1)
				(type default)
			)
			(layer "F.Fab")
		)
		(fp_line
			(start -0.67945 0.3048)
			(end -0.67945 -0.305054)
			(stroke
				(width 0.1)
				(type default)
			)
			(layer "F.Fab")
		)
		(fp_line
			(start -0.67945 -0.305054)
			(end -0.12065 -0.305054)
			(stroke
				(width 0.1)
				(type default)
			)
			(layer "F.Fab")
		)
		(pad "1" smd circle
			(at -0.40005 0 180)
			(size 0 0)
			(layers "F.Cu" "F.Mask" "F.Paste")
			(net "SMB_NIC3_SDA")
		)
		(pad "2" smd circle
			(at 0.40005 0 180)
			(size 0 0)
			(layers "F.Cu" "F.Mask" "F.Paste")
			(net "SMB_NIC3_R_SDA")
		)
	)
	(footprint ""
		(layer "F.Cu")
		(at 9.446768 -154.256994)
		(property "Reference" "PC610"
			(at 0 0 0)
			(layer "F.SilkS")
			(hide yes)
			(effects
				(font
					(size 1.27 1.27)
				)
			)
		)
		(property "Value" ""
			(at 0 0 0)
			(layer "F.Fab")
			(effects
				(font
					(size 1.27 1.27)
				)
			)
		)
		(duplicate_pad_numbers_are_jumpers no)
		(fp_line
			(start -1.2954 -0.5842)
			(end 1.2954 -0.5842)
			(stroke
				(width 0.1524)
				(type default)
			)
			(layer "F.SilkS")
		)
		(fp_line
			(start -1.2954 0.5842)
			(end -1.2954 -0.5842)
			(stroke
				(width 0.1524)
				(type default)
			)
			(layer "F.SilkS")
		)
		(fp_line
			(start 1.2954 -0.5842)
			(end 1.2954 0.5842)
			(stroke
				(width 0.1524)
				(type default)
			)
			(layer "F.SilkS")
		)
		(fp_line
			(start 1.2954 0.5842)
			(end -1.2954 0.5842)
			(stroke
				(width 0.1524)
				(type default)
			)
			(layer "F.SilkS")
		)
		(fp_line
			(start -1.1938 -0.4064)
			(end -0.8636 -0.4064)
			(stroke
				(width 0.1)
				(type default)
			)
			(layer "F.Fab")
		)
		(fp_line
			(start -1.1938 0.4064)
			(end -1.1938 -0.4064)
			(stroke
				(width 0.1)
				(type default)
			)
			(layer "F.Fab")
		)
		(fp_line
			(start -0.8636 -0.4572)
			(end 0.8636 -0.4572)
			(stroke
				(width 0.1)
				(type default)
			)
			(layer "F.Fab")
		)
		(fp_line
			(start -0.8636 -0.4064)
			(end -0.8636 -0.4572)
			(stroke
				(width 0.1)
				(type default)
			)
			(layer "F.Fab")
		)
		(fp_line
			(start -0.8636 0.4064)
			(end -1.1938 0.4064)
			(stroke
				(width 0.1)
				(type default)
			)
			(layer "F.Fab")
		)
		(fp_line
			(start -0.8636 0.4572)
			(end -0.8636 0.4064)
			(stroke
				(width 0.1)
				(type default)
			)
			(layer "F.Fab")
		)
		(fp_line
			(start 0.8636 -0.4572)
			(end 0.8636 -0.4064)
			(stroke
				(width 0.1)
				(type default)
			)
			(layer "F.Fab")
		)
		(fp_line
			(start 0.8636 -0.4064)
			(end 1.1938 -0.4064)
			(stroke
				(width 0.1)
				(type default)
			)
			(layer "F.Fab")
		)
		(fp_line
			(start 0.8636 0.4064)
			(end 0.8636 0.4572)
			(stroke
				(width 0.1)
				(type default)
			)
			(layer "F.Fab")
		)
		(fp_line
			(start 0.8636 0.4572)
			(end -0.8636 0.4572)
			(stroke
				(width 0.1)
				(type default)
			)
			(layer "F.Fab")
		)
		(fp_line
			(start 1.1938 -0.4064)
			(end 1.1938 0.4064)
			(stroke
				(width 0.1)
				(type default)
			)
			(layer "F.Fab")
		)
		(fp_line
			(start 1.1938 0.4064)
			(end 0.8636 0.4064)
			(stroke
				(width 0.1)
				(type default)
			)
			(layer "F.Fab")
		)
		(pad "1" smd rect
			(at -0.7366 0 270)
			(size 0.7112 0.8128)
			(layers "F.Cu" "F.Mask" "F.Paste")
			(net "GND")
		)
		(pad "2" smd rect
			(at 0.7366 0 270)
			(size 0.7112 0.8128)
			(layers "F.Cu" "F.Mask" "F.Paste")
			(net "P12V_NIC0_CO_AVIN_PD")
		)
	)
	(footprint ""
		(layer "F.Cu")
		(at 3.50012 -311.410096)
		(property "Reference" "H133"
			(at -1.870202 -4.598924 0)
			(unlocked yes)
			(layer "F.SilkS")
			(effects
				(font
					(size 0.7874 0.5842)
					(thickness 0.1524)
				)
				(justify left)
			)
		)
		(property "Value" ""
			(at 0 0 0)
			(layer "F.Fab")
			(effects
				(font
					(size 1.27 1.27)
				)
			)
		)
		(duplicate_pad_numbers_are_jumpers no)
		(pad "1" thru_hole circle
			(at 0 0)
			(size 6.5024 6.5024)
			(drill 3.2004)
			(layers "*.Cu" "*.Mask")
			(remove_unused_layers no)
			(net "GND")
			(clearance -1.397)
		)
	)
)
